(kicad_pcb
	(version 20260206)
	(generator "pcbnew")
	(generator_version "10.0")
	(general
		(thickness 1.6)
		(legacy_teardrops no)
	)
	(paper "A4")
	(title_block
		(title "04192023_DAF0TMB3IC0_F0TG_MB_C_brd_V02_OCP.brd")
		(comment 1 "Grand Teton / footprints 6791-6796 of 8354")
	)
	(layers
		(0 "F.Cu" signal "TOP")
		(4 "In1.Cu" signal "GND")
		(6 "In2.Cu" signal "IN1")
		(8 "In3.Cu" signal "GND1")
		(10 "In4.Cu" signal "IN2")
		(12 "In5.Cu" signal "GND2")
		(14 "In6.Cu" signal "IN3")
		(16 "In7.Cu" signal "GND3")
		(18 "In8.Cu" signal "VCC")
		(20 "In9.Cu" signal "VCC1")
		(22 "In10.Cu" signal "GND4")
		(24 "In11.Cu" signal "IN4")
		(26 "In12.Cu" signal "GND5")
		(28 "In13.Cu" signal "IN5")
		(30 "In14.Cu" signal "GND6")
		(32 "In15.Cu" signal "IN6")
		(34 "In16.Cu" signal "GND7")
		(2 "B.Cu" signal "BOTTOM")
		(9 "F.Adhes" user "F.Adhesive")
		(11 "B.Adhes" user "B.Adhesive")
		(13 "F.Paste" user "Package Geometry/Pastemask Top")
		(15 "B.Paste" user "Package Geometry/Pastemask Bottom")
		(5 "F.SilkS" user "Ref Des/Silkscreen Top")
		(7 "B.SilkS" user "Ref Des/Silkscreen Bottom")
		(1 "F.Mask" user "Board Geometry/Soldermask Top")
		(3 "B.Mask" user "Board Geometry/Soldermask Bottom")
		(17 "Dwgs.User" user "User.Drawings")
		(19 "Cmts.User" user "User.Comments")
		(21 "Eco1.User" user "User.Eco1")
		(23 "Eco2.User" user "User.Eco2")
		(25 "Edge.Cuts" user "Board Geometry/Outline")
		(27 "Margin" user)
		(31 "F.CrtYd" user "Package Geometry/Place Bound Top")
		(29 "B.CrtYd" user "Package Geometry/Place Bound Bottom")
		(35 "F.Fab" user "Ref Des/Assembly Top")
		(33 "B.Fab" user "Ref Des/Assembly Bottom")
	)
	(footprint ""
		(layer "B.Cu")
		(at 368.199924 -396.991078 90)
		(property "Reference" "C1053"
			(at 0 0 90)
			(layer "B.SilkS")
			(hide yes)
			(effects
				(font
					(size 1.27 1.27)
				)
				(justify mirror)
			)
		)
		(property "Value" ""
			(at 0 0 90)
			(layer "B.Fab")
			(effects
				(font
					(size 1.27 1.27)
				)
				(justify mirror)
			)
		)
		(duplicate_pad_numbers_are_jumpers no)
		(fp_line
			(start 0.299974 -0.150114)
			(end -0.299974 -0.150114)
			(stroke
				(width 0.1)
				(type default)
			)
			(layer "B.Fab")
		)
		(fp_line
			(start -0.299974 -0.150114)
			(end -0.299974 0.150114)
			(stroke
				(width 0.1)
				(type default)
			)
			(layer "B.Fab")
		)
		(fp_line
			(start 0.299974 0.150114)
			(end 0.299974 -0.150114)
			(stroke
				(width 0.1)
				(type default)
			)
			(layer "B.Fab")
		)
		(fp_line
			(start -0.299974 0.150114)
			(end 0.299974 0.150114)
			(stroke
				(width 0.1)
				(type default)
			)
			(layer "B.Fab")
		)
		(pad "1" smd rect
			(at 0.2667 0 270)
			(size 0.3048 0.381)
			(layers "B.Cu" "B.Mask" "B.Paste")
			(net "P0V9_CPU0_RT3_2A")
		)
		(pad "2" smd rect
			(at -0.2667 0 270)
			(size 0.3048 0.381)
			(layers "B.Cu" "B.Mask" "B.Paste")
			(net "GND")
		)
	)
	(footprint ""
		(layer "B.Cu")
		(at 139.679426 -9.058148 -90)
		(property "Reference" "R1798"
			(at 0 0 90)
			(layer "B.SilkS")
			(hide yes)
			(effects
				(font
					(size 1.27 1.27)
				)
				(justify mirror)
			)
		)
		(property "Value" ""
			(at 0 0 90)
			(layer "B.Fab")
			(effects
				(font
					(size 1.27 1.27)
				)
				(justify mirror)
			)
		)
		(duplicate_pad_numbers_are_jumpers no)
		(fp_line
			(start -0.7874 0.4064)
			(end 0.7874 0.4064)
			(stroke
				(width 0.1524)
				(type default)
			)
			(layer "B.SilkS")
		)
		(fp_line
			(start 0.7874 0.4064)
			(end 0.7874 -0.4064)
			(stroke
				(width 0.1524)
				(type default)
			)
			(layer "B.SilkS")
		)
		(fp_line
			(start -0.7874 -0.4064)
			(end -0.7874 0.4064)
			(stroke
				(width 0.1524)
				(type default)
			)
			(layer "B.SilkS")
		)
		(fp_line
			(start 0.7874 -0.4064)
			(end -0.7874 -0.4064)
			(stroke
				(width 0.1524)
				(type default)
			)
			(layer "B.SilkS")
		)
		(fp_line
			(start -0.67945 0.3048)
			(end -0.120396 0.3048)
			(stroke
				(width 0.1)
				(type default)
			)
			(layer "B.Fab")
		)
		(fp_line
			(start -0.120396 0.3048)
			(end -0.120396 0.2794)
			(stroke
				(width 0.1)
				(type default)
			)
			(layer "B.Fab")
		)
		(fp_line
			(start 0.12065 0.3048)
			(end 0.67945 0.3048)
			(stroke
				(width 0.1)
				(type default)
			)
			(layer "B.Fab")
		)
		(fp_line
			(start 0.67945 0.3048)
			(end 0.67945 -0.305054)
			(stroke
				(width 0.1)
				(type default)
			)
			(layer "B.Fab")
		)
		(fp_line
			(start -0.120396 0.2794)
			(end 0.12065 0.2794)
			(stroke
				(width 0.1)
				(type default)
			)
			(layer "B.Fab")
		)
		(fp_line
			(start 0.12065 0.2794)
			(end 0.12065 0.3048)
			(stroke
				(width 0.1)
				(type default)
			)
			(layer "B.Fab")
		)
		(fp_line
			(start -0.12065 -0.2794)
			(end -0.12065 -0.3048)
			(stroke
				(width 0.1)
				(type default)
			)
			(layer "B.Fab")
		)
		(fp_line
			(start 0.12065 -0.2794)
			(end -0.12065 -0.2794)
			(stroke
				(width 0.1)
				(type default)
			)
			(layer "B.Fab")
		)
		(fp_line
			(start -0.67945 -0.3048)
			(end -0.67945 0.3048)
			(stroke
				(width 0.1)
				(type default)
			)
			(layer "B.Fab")
		)
		(fp_line
			(start -0.12065 -0.3048)
			(end -0.67945 -0.3048)
			(stroke
				(width 0.1)
				(type default)
			)
			(layer "B.Fab")
		)
		(fp_line
			(start 0.12065 -0.305054)
			(end 0.12065 -0.2794)
			(stroke
				(width 0.1)
				(type default)
			)
			(layer "B.Fab")
		)
		(fp_line
			(start 0.67945 -0.305054)
			(end 0.12065 -0.305054)
			(stroke
				(width 0.1)
				(type default)
			)
			(layer "B.Fab")
		)
		(pad "1" smd circle
			(at 0.40005 0 90)
			(size 0 0)
			(layers "B.Cu" "B.Mask" "B.Paste")
			(net "SCM_ROT_CPU_RST_R_N")
		)
		(pad "2" smd circle
			(at -0.40005 0 90)
			(size 0 0)
			(layers "B.Cu" "B.Mask" "B.Paste")
			(net "SCM_ROT_CPU_RST_N")
		)
	)
	(footprint ""
		(layer "B.Cu")
		(at 208.461356 -378.682504)
		(property "Reference" "PR2515"
			(at 0 0 0)
			(layer "B.SilkS")
			(hide yes)
			(effects
				(font
					(size 1.27 1.27)
				)
				(justify mirror)
			)
		)
		(property "Value" ""
			(at 0 0 0)
			(layer "B.Fab")
			(effects
				(font
					(size 1.27 1.27)
				)
				(justify mirror)
			)
		)
		(duplicate_pad_numbers_are_jumpers no)
		(fp_line
			(start -0.7874 -0.4064)
			(end -0.7874 0.4064)
			(stroke
				(width 0.1524)
				(type default)
			)
			(layer "B.SilkS")
		)
		(fp_line
			(start -0.7874 0.4064)
			(end 0.7874 0.4064)
			(stroke
				(width 0.1524)
				(type default)
			)
			(layer "B.SilkS")
		)
		(fp_line
			(start 0.7874 -0.4064)
			(end -0.7874 -0.4064)
			(stroke
				(width 0.1524)
				(type default)
			)
			(layer "B.SilkS")
		)
		(fp_line
			(start 0.7874 0.4064)
			(end 0.7874 -0.4064)
			(stroke
				(width 0.1524)
				(type default)
			)
			(layer "B.SilkS")
		)
		(fp_line
			(start -0.67945 -0.3048)
			(end -0.67945 0.3048)
			(stroke
				(width 0.1)
				(type default)
			)
			(layer "B.Fab")
		)
		(fp_line
			(start -0.67945 0.3048)
			(end -0.120396 0.3048)
			(stroke
				(width 0.1)
				(type default)
			)
			(layer "B.Fab")
		)
		(fp_line
			(start -0.12065 -0.3048)
			(end -0.67945 -0.3048)
			(stroke
				(width 0.1)
				(type default)
			)
			(layer "B.Fab")
		)
		(fp_line
			(start -0.12065 -0.2794)
			(end -0.12065 -0.3048)
			(stroke
				(width 0.1)
				(type default)
			)
			(layer "B.Fab")
		)
		(fp_line
			(start -0.120396 0.2794)
			(end 0.12065 0.2794)
			(stroke
				(width 0.1)
				(type default)
			)
			(layer "B.Fab")
		)
		(fp_line
			(start -0.120396 0.3048)
			(end -0.120396 0.2794)
			(stroke
				(width 0.1)
				(type default)
			)
			(layer "B.Fab")
		)
		(fp_line
			(start 0.12065 -0.305054)
			(end 0.12065 -0.2794)
			(stroke
				(width 0.1)
				(type default)
			)
			(layer "B.Fab")
		)
		(fp_line
			(start 0.12065 -0.2794)
			(end -0.12065 -0.2794)
			(stroke
				(width 0.1)
				(type default)
			)
			(layer "B.Fab")
		)
		(fp_line
			(start 0.12065 0.2794)
			(end 0.12065 0.3048)
			(stroke
				(width 0.1)
				(type default)
			)
			(layer "B.Fab")
		)
		(fp_line
			(start 0.12065 0.3048)
			(end 0.67945 0.3048)
			(stroke
				(width 0.1)
				(type default)
			)
			(layer "B.Fab")
		)
		(fp_line
			(start 0.67945 -0.305054)
			(end 0.12065 -0.305054)
			(stroke
				(width 0.1)
				(type default)
			)
			(layer "B.Fab")
		)
		(fp_line
			(start 0.67945 0.3048)
			(end 0.67945 -0.305054)
			(stroke
				(width 0.1)
				(type default)
			)
			(layer "B.Fab")
		)
		(pad "1" smd circle
			(at 0.40005 0 180)
			(size 0 0)
			(layers "B.Cu" "B.Mask" "B.Paste")
			(net "P12V_HSC_ADC_N")
		)
		(pad "2" smd circle
			(at -0.40005 0 180)
			(size 0 0)
			(layers "B.Cu" "B.Mask" "B.Paste")
			(net "P12V_HSC_SENSE2_R1_N")
		)
	)
	(footprint ""
		(layer "B.Cu")
		(at 351.739454 -255.84531 180)
		(property "Reference" "C2575"
			(at 0 0 0)
			(layer "B.SilkS")
			(hide yes)
			(effects
				(font
					(size 1.27 1.27)
				)
				(justify mirror)
			)
		)
		(property "Value" ""
			(at 0 0 0)
			(layer "B.Fab")
			(effects
				(font
					(size 1.27 1.27)
				)
				(justify mirror)
			)
		)
		(duplicate_pad_numbers_are_jumpers no)
		(fp_line
			(start 0.7874 0.4064)
			(end 0.7874 -0.4064)
			(stroke
				(width 0.1524)
				(type default)
			)
			(layer "B.SilkS")
		)
		(fp_line
			(start 0.7874 -0.4064)
			(end -0.7874 -0.4064)
			(stroke
				(width 0.1524)
				(type default)
			)
			(layer "B.SilkS")
		)
		(fp_line
			(start -0.7874 0.4064)
			(end 0.7874 0.4064)
			(stroke
				(width 0.1524)
				(type default)
			)
			(layer "B.SilkS")
		)
		(fp_line
			(start -0.7874 -0.4064)
			(end -0.7874 0.4064)
			(stroke
				(width 0.1524)
				(type default)
			)
			(layer "B.SilkS")
		)
		(fp_line
			(start 0.67945 0.3048)
			(end 0.67945 -0.305054)
			(stroke
				(width 0.1)
				(type default)
			)
			(layer "B.Fab")
		)
		(fp_line
			(start 0.67945 -0.305054)
			(end 0.12065 -0.305054)
			(stroke
				(width 0.1)
				(type default)
			)
			(layer "B.Fab")
		)
		(fp_line
			(start 0.12065 0.3048)
			(end 0.67945 0.3048)
			(stroke
				(width 0.1)
				(type default)
			)
			(layer "B.Fab")
		)
		(fp_line
			(start 0.12065 0.2794)
			(end 0.12065 0.3048)
			(stroke
				(width 0.1)
				(type default)
			)
			(layer "B.Fab")
		)
		(fp_line
			(start 0.12065 -0.2794)
			(end -0.12065 -0.2794)
			(stroke
				(width 0.1)
				(type default)
			)
			(layer "B.Fab")
		)
		(fp_line
			(start 0.12065 -0.305054)
			(end 0.12065 -0.2794)
			(stroke
				(width 0.1)
				(type default)
			)
			(layer "B.Fab")
		)
		(fp_line
			(start -0.120396 0.3048)
			(end -0.120396 0.2794)
			(stroke
				(width 0.1)
				(type default)
			)
			(layer "B.Fab")
		)
		(fp_line
			(start -0.120396 0.2794)
			(end 0.12065 0.2794)
			(stroke
				(width 0.1)
				(type default)
			)
			(layer "B.Fab")
		)
		(fp_line
			(start -0.12065 -0.2794)
			(end -0.12065 -0.3048)
			(stroke
				(width 0.1)
				(type default)
			)
			(layer "B.Fab")
		)
		(fp_line
			(start -0.12065 -0.3048)
			(end -0.67945 -0.3048)
			(stroke
				(width 0.1)
				(type default)
			)
			(layer "B.Fab")
		)
		(fp_line
			(start -0.67945 0.3048)
			(end -0.120396 0.3048)
			(stroke
				(width 0.1)
				(type default)
			)
			(layer "B.Fab")
		)
		(fp_line
			(start -0.67945 -0.3048)
			(end -0.67945 0.3048)
			(stroke
				(width 0.1)
				(type default)
			)
			(layer "B.Fab")
		)
		(pad "1" smd circle
			(at 0.40005 0)
			(size 0 0)
			(layers "B.Cu" "B.Mask" "B.Paste")
			(net "PVDDCR_SOC_P0")
		)
		(pad "2" smd circle
			(at -0.40005 0)
			(size 0 0)
			(layers "B.Cu" "B.Mask" "B.Paste")
			(net "GND")
		)
	)
	(footprint ""
		(layer "B.Cu")
		(at 69.861684 -390.073134 180)
		(property "Reference" "C225"
			(at 0 0 0)
			(layer "B.SilkS")
			(hide yes)
			(effects
				(font
					(size 1.27 1.27)
				)
				(justify mirror)
			)
		)
		(property "Value" ""
			(at 0 0 0)
			(layer "B.Fab")
			(effects
				(font
					(size 1.27 1.27)
				)
				(justify mirror)
			)
		)
		(duplicate_pad_numbers_are_jumpers no)
		(fp_line
			(start 1.524 0.762)
			(end 1.524 -0.762)
			(stroke
				(width 0.1524)
				(type default)
			)
			(layer "B.SilkS")
		)
		(fp_line
			(start 1.524 -0.762)
			(end -1.524 -0.762)
			(stroke
				(width 0.1524)
				(type default)
			)
			(layer "B.SilkS")
		)
		(fp_line
			(start -1.524 0.762)
			(end 1.524 0.762)
			(stroke
				(width 0.1524)
				(type default)
			)
			(layer "B.SilkS")
		)
		(fp_line
			(start -1.524 -0.762)
			(end -1.524 0.762)
			(stroke
				(width 0.1524)
				(type default)
			)
			(layer "B.SilkS")
		)
		(fp_line
			(start 1.1049 0.724916)
			(end -1.1049 0.724916)
			(stroke
				(width 0.1)
				(type default)
			)
			(layer "B.Fab")
		)
		(fp_line
			(start 1.1049 -0.724916)
			(end 1.1049 0.724916)
			(stroke
				(width 0.1)
				(type default)
			)
			(layer "B.Fab")
		)
		(fp_line
			(start -1.1049 0.724916)
			(end -1.1049 -0.724916)
			(stroke
				(width 0.1)
				(type default)
			)
			(layer "B.Fab")
		)
		(fp_line
			(start -1.1049 -0.724916)
			(end 1.1049 -0.724916)
			(stroke
				(width 0.1)
				(type default)
			)
			(layer "B.Fab")
		)
		(pad "1" smd rect
			(at 0.889 0 180)
			(size 1.016 1.27)
			(layers "B.Cu" "B.Mask" "B.Paste")
			(net "P0V9_CPU1_RT0_2A")
		)
		(pad "2" smd rect
			(at -0.889 0 180)
			(size 1.016 1.27)
			(layers "B.Cu" "B.Mask" "B.Paste")
			(net "GND")
		)
	)
	(footprint ""
		(layer "B.Cu")
		(at 104.521762 -410.3116 180)
		(property "Reference" "C98"
			(at 0 0 0)
			(layer "B.SilkS")
			(hide yes)
			(effects
				(font
					(size 1.27 1.27)
				)
				(justify mirror)
			)
		)
		(property "Value" ""
			(at 0 0 0)
			(layer "B.Fab")
			(effects
				(font
					(size 1.27 1.27)
				)
				(justify mirror)
			)
		)
		(duplicate_pad_numbers_are_jumpers no)
		(fp_line
			(start 0.7874 0.4064)
			(end 0.7874 -0.4064)
			(stroke
				(width 0.1524)
				(type default)
			)
			(layer "B.SilkS")
		)
		(fp_line
			(start 0.7874 -0.4064)
			(end -0.7874 -0.4064)
			(stroke
				(width 0.1524)
				(type default)
			)
			(layer "B.SilkS")
		)
		(fp_line
			(start -0.7874 0.4064)
			(end 0.7874 0.4064)
			(stroke
				(width 0.1524)
				(type default)
			)
			(layer "B.SilkS")
		)
		(fp_line
			(start -0.7874 -0.4064)
			(end -0.7874 0.4064)
			(stroke
				(width 0.1524)
				(type default)
			)
			(layer "B.SilkS")
		)
		(fp_line
			(start 0.67945 0.3048)
			(end 0.67945 -0.305054)
			(stroke
				(width 0.1)
				(type default)
			)
			(layer "B.Fab")
		)
		(fp_line
			(start 0.67945 -0.305054)
			(end 0.12065 -0.305054)
			(stroke
				(width 0.1)
				(type default)
			)
			(layer "B.Fab")
		)
		(fp_line
			(start 0.12065 0.3048)
			(end 0.67945 0.3048)
			(stroke
				(width 0.1)
				(type default)
			)
			(layer "B.Fab")
		)
		(fp_line
			(start 0.12065 0.2794)
			(end 0.12065 0.3048)
			(stroke
				(width 0.1)
				(type default)
			)
			(layer "B.Fab")
		)
		(fp_line
			(start 0.12065 -0.2794)
			(end -0.12065 -0.2794)
			(stroke
				(width 0.1)
				(type default)
			)
			(layer "B.Fab")
		)
		(fp_line
			(start 0.12065 -0.305054)
			(end 0.12065 -0.2794)
			(stroke
				(width 0.1)
				(type default)
			)
			(layer "B.Fab")
		)
		(fp_line
			(start -0.120396 0.3048)
			(end -0.120396 0.2794)
			(stroke
				(width 0.1)
				(type default)
			)
			(layer "B.Fab")
		)
		(fp_line
			(start -0.120396 0.2794)
			(end 0.12065 0.2794)
			(stroke
				(width 0.1)
				(type default)
			)
			(layer "B.Fab")
		)
		(fp_line
			(start -0.12065 -0.2794)
			(end -0.12065 -0.3048)
			(stroke
				(width 0.1)
				(type default)
			)
			(layer "B.Fab")
		)
		(fp_line
			(start -0.12065 -0.3048)
			(end -0.67945 -0.3048)
			(stroke
				(width 0.1)
				(type default)
			)
			(layer "B.Fab")
		)
		(fp_line
			(start -0.67945 0.3048)
			(end -0.120396 0.3048)
			(stroke
				(width 0.1)
				(type default)
			)
			(layer "B.Fab")
		)
		(fp_line
			(start -0.67945 -0.3048)
			(end -0.67945 0.3048)
			(stroke
				(width 0.1)
				(type default)
			)
			(layer "B.Fab")
		)
		(pad "1" smd circle
			(at 0.40005 0)
			(size 0 0)
			(layers "B.Cu" "B.Mask" "B.Paste")
			(net "P3V3_9ZXL045_P1_VDD")
		)
		(pad "2" smd circle
			(at -0.40005 0)
			(size 0 0)
			(layers "B.Cu" "B.Mask" "B.Paste")
			(net "GND")
		)
	)
)
